(kicad_pcb
	(version 20260206)
	(generator "pcbnew")
	(generator_version "10.0")
	(general
		(thickness 1.6)
		(legacy_teardrops no)
	)
	(paper "A4")
	(title_block
		(title "dpb — 14545-sa.0730WZS0815.brd")
		(comment 1 "Honey Badger (Wiwynn) / footprints 603-607 of 1066")
	)
	(layers
		(0 "F.Cu" signal "TOP")
		(4 "In1.Cu" signal "L2GND")
		(6 "In2.Cu" signal "L3")
		(8 "In3.Cu" signal "L4VCC")
		(10 "In4.Cu" signal "L5VCC")
		(12 "In5.Cu" signal "L6")
		(14 "In6.Cu" signal "L7GND")
		(2 "B.Cu" signal "BOTTOM")
		(9 "F.Adhes" user "F.Adhesive")
		(11 "B.Adhes" user "B.Adhesive")
		(13 "F.Paste" user "Package Geometry/Pastemask Top")
		(15 "B.Paste" user "Package Geometry/Pastemask Bottom")
		(5 "F.SilkS" user "Ref Des/Silkscreen Top")
		(7 "B.SilkS" user "Ref Des/Silkscreen Bottom")
		(1 "F.Mask" user "Board Geometry/Soldermask Top")
		(3 "B.Mask" user "Board Geometry/Soldermask Bottom")
		(17 "Dwgs.User" user "User.Drawings")
		(19 "Cmts.User" user "User.Comments")
		(21 "Eco1.User" user "User.Eco1")
		(23 "Eco2.User" user "User.Eco2")
		(25 "Edge.Cuts" user "Board Geometry/Outline")
		(27 "Margin" user)
		(31 "F.CrtYd" user "Package Geometry/Place Bound Top")
		(29 "B.CrtYd" user "Package Geometry/Place Bound Bottom")
		(35 "F.Fab" user "Ref Des/Assembly Top")
		(33 "B.Fab" user "Ref Des/Assembly Bottom")
	)
	(footprint ""
		(layer "F.Cu")
		(at 223.647 -437.261 -90)
		(property "Reference" "D14"
			(at 0 0 270)
			(layer "F.SilkS")
			(hide yes)
			(effects
				(font
					(size 1.27 1.27)
				)
			)
		)
		(property "Value" "NSR0520V2T1G-GP"
			(at 0 -4.690618 270)
			(unlocked yes)
			(layer "F.Fab")
			(hide yes)
			(effects
				(font
					(size 1.016 1.016)
					(thickness 0.1524)
				)
			)
		)
		(property "Device Type" "SOD523AKH28"
			(at 0 -6.214618 270)
			(unlocked yes)
			(layer "F.Fab")
			(hide yes)
			(effects
				(font
					(size 1.016 1.016)
					(thickness 0.1524)
				)
			)
		)
		(duplicate_pad_numbers_are_jumpers no)
		(fp_line
			(start -0.7112 1.7018)
			(end 0.7112 1.7018)
			(stroke
				(width 0.508)
				(type default)
			)
			(layer "F.SilkS")
		)
		(fp_line
			(start 0.7112 1.7018)
			(end 0.7112 0.4699)
			(stroke
				(width 0.508)
				(type default)
			)
			(layer "F.SilkS")
		)
		(fp_line
			(start -0.5334 1.524)
			(end 0.5334 1.524)
			(stroke
				(width 0.1524)
				(type default)
			)
			(layer "F.SilkS")
		)
		(fp_line
			(start 0.5334 1.524)
			(end 0.5334 -1.524)
			(stroke
				(width 0.1524)
				(type default)
			)
			(layer "F.SilkS")
		)
		(fp_line
			(start -0.7112 0.4699)
			(end -0.7112 1.7018)
			(stroke
				(width 0.508)
				(type default)
			)
			(layer "F.SilkS")
		)
		(fp_line
			(start -0.5334 -1.524)
			(end -0.5334 1.524)
			(stroke
				(width 0.1524)
				(type default)
			)
			(layer "F.SilkS")
		)
		(fp_line
			(start -0.5334 -1.524)
			(end 0.5334 -1.524)
			(stroke
				(width 0.1524)
				(type default)
			)
			(layer "F.SilkS")
		)
		(fp_poly
			(pts
				(xy -0.1524 0.8001) (xy -0.1524 0.5969) (xy -0.4064 0.5969) (xy -0.4064 -0.5969) (xy -0.1524 -0.5969)
				(xy -0.1524 -0.8001) (xy 0.1524 -0.8001) (xy 0.1524 -0.5969) (xy 0.4064 -0.5969) (xy 0.4064 0.5969)
				(xy 0.1524 0.5969) (xy 0.1524 0.8001)
			)
			(stroke
				(width 0)
				(type default)
			)
			(fill no)
			(layer "F.CrtYd")
		)
		(fp_poly
			(pts
				(xy -0.6096 1.6002) (xy -0.6096 -1.6002) (xy 0.6096 -1.6002) (xy 0.6096 -0.1397) (xy 0.4064 -0.1397)
				(xy 0.4064 -0.5969) (xy 0.1524 -0.5969) (xy 0.1524 -0.8001) (xy -0.1524 -0.8001) (xy -0.1524 -0.5969)
				(xy -0.4064 -0.5969) (xy -0.4064 0.5969) (xy -0.1524 0.5969) (xy -0.1524 0.8001) (xy 0.1524 0.8001)
				(xy 0.1524 0.5969) (xy 0.4064 0.5969) (xy 0.4064 -0.127) (xy 0.6096 -0.127) (xy 0.6096 1.6002)
			)
			(stroke
				(width 0)
				(type default)
			)
			(fill no)
			(layer "F.CrtYd")
		)
		(fp_rect
			(start -0.6096 1.6002)
			(end 0.6096 -1.6002)
			(stroke
				(width 0)
				(type default)
			)
			(fill no)
			(layer "F.Fab")
		)
		(pad "A" smd rect
			(at 0 -0.762 270)
			(size 0.5588 1.016)
			(layers "F.Cu" "F.Mask" "F.Paste")
			(net "P3V3_EN")
		)
		(pad "K" smd rect
			(at 0 0.762 270)
			(size 0.5588 1.016)
			(layers "F.Cu" "F.Mask" "F.Paste")
			(net "P3V3_IN")
		)
	)
	(footprint ""
		(layer "F.Cu")
		(at 189.865 -292.989)
		(property "Reference" "R137"
			(at 0 0 0)
			(layer "F.SilkS")
			(hide yes)
			(effects
				(font
					(size 1.27 1.27)
				)
			)
		)
		(property "Value" "200KR2F-L-GP"
			(at 0.064008 -3.993896 0)
			(unlocked yes)
			(layer "F.Fab")
			(hide yes)
			(effects
				(font
					(size 1.016 1.016)
					(thickness 0.1524)
				)
			)
		)
		(property "Device Type" "R402H16"
			(at 0.064008 -5.517896 0)
			(unlocked yes)
			(layer "F.Fab")
			(hide yes)
			(effects
				(font
					(size 1.016 1.016)
					(thickness 0.1524)
				)
			)
		)
		(duplicate_pad_numbers_are_jumpers no)
		(fp_line
			(start -0.508 -0.9398)
			(end -0.508 0.9398)
			(stroke
				(width 0.1524)
				(type default)
			)
			(layer "F.SilkS")
		)
		(fp_line
			(start 0.508 -0.9398)
			(end -0.508 -0.9398)
			(stroke
				(width 0.1524)
				(type default)
			)
			(layer "F.SilkS")
		)
		(fp_rect
			(start -0.508 0.9398)
			(end 0.508 -0.9398)
			(stroke
				(width 0)
				(type default)
			)
			(fill no)
			(layer "F.CrtYd")
		)
		(fp_rect
			(start -0.508 0.9398)
			(end 0.508 -0.9398)
			(stroke
				(width 0)
				(type default)
			)
			(fill no)
			(layer "F.Fab")
		)
		(pad "1" smd custom
			(at 0 -0.4445)
			(size 0.1397 0.1397)
			(layers "F.Cu" "F.Mask" "F.Paste")
			(net "P12V")
			(options
				(clearance outline)
				(anchor circle)
			)
			(primitives
				(gr_poly
					(pts
						(arc
							(start -0.1778 -0.2794)
							(mid -0.249642 -0.249642)
							(end -0.2794 -0.1778)
						)
						(arc
							(start -0.2794 0.1778)
							(mid -0.249642 0.249642)
							(end -0.1778 0.2794)
						)
						(arc
							(start 0.1778 0.2794)
							(mid 0.249642 0.249642)
							(end 0.2794 0.1778)
						)
						(arc
							(start 0.2794 -0.1778)
							(mid 0.249642 -0.249642)
							(end 0.1778 -0.2794)
						)
					)
					(width 0)
					(fill yes)
				)
			)
		)
		(pad "2" smd custom
			(at 0 0.4445)
			(size 0.1397 0.1397)
			(layers "F.Cu" "F.Mask" "F.Paste")
			(net "SW_HDD2_P")
			(options
				(clearance outline)
				(anchor circle)
			)
			(primitives
				(gr_poly
					(pts
						(arc
							(start -0.1778 -0.2794)
							(mid -0.249642 -0.249642)
							(end -0.2794 -0.1778)
						)
						(arc
							(start -0.2794 0.1778)
							(mid -0.249642 0.249642)
							(end -0.1778 0.2794)
						)
						(arc
							(start 0.1778 0.2794)
							(mid 0.249642 0.249642)
							(end 0.2794 0.1778)
						)
						(arc
							(start 0.2794 -0.1778)
							(mid 0.249642 -0.249642)
							(end 0.1778 -0.2794)
						)
					)
					(width 0)
					(fill yes)
				)
			)
		)
	)
	(footprint ""
		(layer "F.Cu")
		(at 9.651746 -488.0737 -90)
		(property "Reference" "PC33"
			(at 0 0 270)
			(layer "F.SilkS")
			(hide yes)
			(effects
				(font
					(size 1.27 1.27)
				)
			)
		)
		(property "Value" "SC2200P50V2KX-2GP"
			(at 1.1811 -2.7051 270)
			(unlocked yes)
			(layer "F.Fab")
			(hide yes)
			(effects
				(font
					(size 1.016 1.016)
					(thickness 0.1524)
				)
			)
		)
		(property "Device Type" "C402H22"
			(at 1.1811 -4.2291 270)
			(unlocked yes)
			(layer "F.Fab")
			(hide yes)
			(effects
				(font
					(size 1.016 1.016)
					(thickness 0.1524)
				)
			)
		)
		(duplicate_pad_numbers_are_jumpers no)
		(fp_rect
			(start -0.4318 0.9525)
			(end 0.4318 -0.9525)
			(stroke
				(width 0)
				(type default)
			)
			(fill no)
			(layer "F.CrtYd")
		)
		(fp_rect
			(start -0.4318 0.9525)
			(end 0.4318 -0.9525)
			(stroke
				(width 0)
				(type default)
			)
			(fill no)
			(layer "F.Fab")
		)
		(pad "1" smd custom
			(at 0 -0.4445 270)
			(size 0.1524 0.1524)
			(layers "F.Cu" "F.Mask" "F.Paste")
			(net "P5VC_LL")
			(options
				(clearance outline)
				(anchor circle)
			)
			(primitives
				(gr_poly
					(pts
						(arc
							(start 0.3048 -0.2032)
							(mid 0.275042 -0.275042)
							(end 0.2032 -0.3048)
						)
						(arc
							(start -0.2032 -0.3048)
							(mid -0.275042 -0.275042)
							(end -0.3048 -0.2032)
						)
						(arc
							(start -0.3048 0.2032)
							(mid -0.275042 0.275042)
							(end -0.2032 0.3048)
						)
						(arc
							(start 0.2032 0.3048)
							(mid 0.275042 0.275042)
							(end 0.3048 0.2032)
						)
					)
					(width 0)
					(fill yes)
				)
			)
		)
		(pad "2" smd custom
			(at 0 0.4445 270)
			(size 0.1524 0.1524)
			(layers "F.Cu" "F.Mask" "F.Paste")
			(net "P5VC_SNB")
			(options
				(clearance outline)
				(anchor circle)
			)
			(primitives
				(gr_poly
					(pts
						(arc
							(start 0.3048 -0.2032)
							(mid 0.275042 -0.275042)
							(end 0.2032 -0.3048)
						)
						(arc
							(start -0.2032 -0.3048)
							(mid -0.275042 -0.275042)
							(end -0.3048 -0.2032)
						)
						(arc
							(start -0.3048 0.2032)
							(mid -0.275042 0.275042)
							(end -0.2032 0.3048)
						)
						(arc
							(start 0.2032 0.3048)
							(mid 0.275042 0.275042)
							(end 0.3048 0.2032)
						)
					)
					(width 0)
					(fill yes)
				)
			)
		)
	)
	(footprint ""
		(layer "F.Cu")
		(at 34.925 -303.784 90)
		(property "Reference" "D26"
			(at 0 0 90)
			(layer "F.SilkS")
			(hide yes)
			(effects
				(font
					(size 1.27 1.27)
				)
			)
		)
		(property "Value" "RB551V30-1-GP"
			(at 0 -6.7818 90)
			(unlocked yes)
			(layer "F.Fab")
			(hide yes)
			(effects
				(font
					(size 1.016 1.016)
					(thickness 0.1524)
				)
			)
		)
		(property "Device Type" "SOD323AKH44"
			(at 0 -8.6868 90)
			(unlocked yes)
			(layer "F.Fab")
			(hide yes)
			(effects
				(font
					(size 1.016 1.016)
					(thickness 0.1524)
				)
			)
		)
		(duplicate_pad_numbers_are_jumpers no)
		(fp_line
			(start 0.889 -1.9304)
			(end 0.889 2.159)
			(stroke
				(width 0.1524)
				(type default)
			)
			(layer "F.SilkS")
		)
		(fp_line
			(start -0.889 -1.9304)
			(end 0.889 -1.9304)
			(stroke
				(width 0.1524)
				(type default)
			)
			(layer "F.SilkS")
		)
		(fp_line
			(start 0.762 2.0574)
			(end -0.762 2.0574)
			(stroke
				(width 0.508)
				(type default)
			)
			(layer "F.SilkS")
		)
		(fp_line
			(start 0.889 2.159)
			(end -0.889 2.159)
			(stroke
				(width 0.1524)
				(type default)
			)
			(layer "F.SilkS")
		)
		(fp_line
			(start -0.889 2.159)
			(end -0.889 -1.9304)
			(stroke
				(width 0.1524)
				(type default)
			)
			(layer "F.SilkS")
		)
		(fp_rect
			(start -1.016 2.3114)
			(end 1.016 -2.0066)
			(stroke
				(width 0)
				(type default)
			)
			(fill no)
			(layer "F.CrtYd")
		)
		(fp_poly
			(pts
				(xy -1.016 -2.0066) (xy 1.016 -2.0066) (xy 1.016 2.3114) (xy -1.016 2.3114)
			)
			(stroke
				(width 0)
				(type default)
			)
			(fill no)
			(layer "F.Fab")
		)
		(pad "A" smd rect
			(at 0 -1.143 90)
			(size 0.5588 1.016)
			(layers "F.Cu" "F.Mask" "F.Paste")
			(net "SW_HDD11_R")
		)
		(pad "K" smd rect
			(at 0 1.143 90)
			(size 0.5588 1.016)
			(layers "F.Cu" "F.Mask" "F.Paste")
			(net "SW_HDD11_N")
		)
	)
	(footprint ""
		(layer "F.Cu")
		(at 26.161746 -298.9707 180)
		(property "Reference" "C224"
			(at 0 0 180)
			(layer "F.SilkS")
			(hide yes)
			(effects
				(font
					(size 1.27 1.27)
				)
			)
		)
		(property "Value" "SC10U25V6KX-1GP"
			(at -0.0762 -5.1308 180)
			(unlocked yes)
			(layer "F.Fab")
			(hide yes)
			(effects
				(font
					(size 1.016 1.016)
					(thickness 0.1524)
				)
			)
		)
		(property "Device Type" "C1206H71"
			(at -0.127 -6.6548 180)
			(unlocked yes)
			(layer "F.Fab")
			(hide yes)
			(effects
				(font
					(size 1.016 1.016)
					(thickness 0.1524)
				)
			)
		)
		(duplicate_pad_numbers_are_jumpers no)
		(fp_line
			(start 1.016 2.2352)
			(end -1.016 2.2352)
			(stroke
				(width 0.1524)
				(type default)
			)
			(layer "F.SilkS")
		)
		(fp_line
			(start 1.016 0.8382)
			(end 1.016 2.2352)
			(stroke
				(width 0.1524)
				(type default)
			)
			(layer "F.SilkS")
		)
		(fp_line
			(start 1.016 -2.2352)
			(end 1.016 -0.8382)
			(stroke
				(width 0.1524)
				(type default)
			)
			(layer "F.SilkS")
		)
		(fp_line
			(start -1.016 2.2352)
			(end -1.016 0.8382)
			(stroke
				(width 0.1524)
				(type default)
			)
			(layer "F.SilkS")
		)
		(fp_line
			(start -1.016 -0.8382)
			(end -1.016 -2.2352)
			(stroke
				(width 0.1524)
				(type default)
			)
			(layer "F.SilkS")
		)
		(fp_line
			(start -1.016 -2.2352)
			(end 1.016 -2.2352)
			(stroke
				(width 0.1524)
				(type default)
			)
			(layer "F.SilkS")
		)
		(fp_rect
			(start -1.0922 2.3114)
			(end 1.0922 -2.3114)
			(stroke
				(width 0)
				(type default)
			)
			(fill no)
			(layer "F.CrtYd")
		)
		(fp_poly
			(pts
				(xy 1.0922 -2.3114) (xy 1.0922 2.3114) (xy -1.0922 2.3114) (xy -1.0922 -2.3114)
			)
			(stroke
				(width 0)
				(type default)
			)
			(fill no)
			(layer "F.Fab")
		)
		(pad "1" smd rect
			(at 0 -1.397 180)
			(size 1.651 1.27)
			(layers "F.Cu" "F.Mask" "F.Paste")
			(net "P12V_HDD7")
		)
		(pad "2" smd rect
			(at 0 1.397 180)
			(size 1.651 1.27)
			(layers "F.Cu" "F.Mask" "F.Paste")
			(net "GND")
		)
	)
)
